# S9S_MB_2U (Grand Teton) — schematic netlist excerpt (pin names and nets, part order shuffled) for the footprints in the layout excerpt that follows; sources: Cadence DE-HDL packaged netlist, KiCad conversion of 03242023_DA0F0TMBIJ0_F0T_Motherboard_J_brd_V01_OCP.brd

R4036  Q_RES  4.32K 1% CHIP  pkg 0402LF  page 225 : A = P3V3_AUX ; B = P0V62_CPU0_RST_DDR_VREF
PC2086  Q_CAP  1UF 25V 10% X6S  pkg C0402  page 156 : A = P3V3_OCP_VCC_1 ; B = GND

(kicad_pcb
	(version 20260206)
	(generator "pcbnew")
	(generator_version "10.0")
	(general
		(thickness 1.6)
		(legacy_teardrops no)
	)
	(paper "A4")
	(title_block
		(title "03242023_DA0F0TMBIJ0_F0T_Motherboard_J_brd_V01_OCP.brd")
		(comment 1 "Grand Teton / footprints 2032-2033 of 6105")
	)
	(layers
		(0 "F.Cu" signal "TOP")
		(4 "In1.Cu" signal "GND")
		(6 "In2.Cu" signal "IN1")
		(8 "In3.Cu" signal "GND1")
		(10 "In4.Cu" signal "IN2")
		(12 "In5.Cu" signal "GND2")
		(14 "In6.Cu" signal "IN3")
		(16 "In7.Cu" signal "GND3")
		(18 "In8.Cu" signal "VCC")
		(20 "In9.Cu" signal "VCC1")
		(22 "In10.Cu" signal "GND4")
		(24 "In11.Cu" signal "IN4")
		(26 "In12.Cu" signal "GND5")
		(28 "In13.Cu" signal "IN5")
		(30 "In14.Cu" signal "GND6")
		(32 "In15.Cu" signal "IN6")
		(34 "In16.Cu" signal "GND7")
		(2 "B.Cu" signal "BOTTOM")
		(9 "F.Adhes" user "F.Adhesive")
		(11 "B.Adhes" user "B.Adhesive")
		(13 "F.Paste" user "Package Geometry/Pastemask Top")
		(15 "B.Paste" user "Package Geometry/Pastemask Bottom")
		(5 "F.SilkS" user "Ref Des/Silkscreen Top")
		(7 "B.SilkS" user "Ref Des/Silkscreen Bottom")
		(1 "F.Mask" user "Board Geometry/Soldermask Top")
		(3 "B.Mask" user "Board Geometry/Soldermask Bottom")
		(17 "Dwgs.User" user "User.Drawings")
		(19 "Cmts.User" user "User.Comments")
		(21 "Eco1.User" user "User.Eco1")
		(23 "Eco2.User" user "User.Eco2")
		(25 "Edge.Cuts" user "Board Geometry/Outline")
		(27 "Margin" user)
		(31 "F.CrtYd" user "Package Geometry/Place Bound Top")
		(29 "B.CrtYd" user "Package Geometry/Place Bound Bottom")
		(35 "F.Fab" user "Ref Des/Assembly Top")
		(33 "B.Fab" user "Ref Des/Assembly Bottom")
	)
	(footprint ""
		(layer "F.Cu")
		(at 114.68608 -119.846598 -90)
		(property "Reference" "R4036"
			(at 0 0 270)
			(layer "F.SilkS")
			(hide yes)
			(effects
				(font
					(size 1.27 1.27)
				)
			)
		)
		(property "Value" ""
			(at 0 0 270)
			(layer "F.Fab")
			(effects
				(font
					(size 1.27 1.27)
				)
			)
		)
		(duplicate_pad_numbers_are_jumpers no)
		(fp_line
			(start -0.7874 0.4064)
			(end -0.7874 -0.4064)
			(stroke
				(width 0.1524)
				(type default)
			)
			(layer "F.SilkS")
		)
		(fp_line
			(start 0.7874 0.4064)
			(end -0.7874 0.4064)
			(stroke
				(width 0.1524)
				(type default)
			)
			(layer "F.SilkS")
		)
		(fp_line
			(start -0.7874 -0.4064)
			(end 0.7874 -0.4064)
			(stroke
				(width 0.1524)
				(type default)
			)
			(layer "F.SilkS")
		)
		(fp_line
			(start 0.7874 -0.4064)
			(end 0.7874 0.4064)
			(stroke
				(width 0.1524)
				(type default)
			)
			(layer "F.SilkS")
		)
		(fp_line
			(start -0.67945 0.3048)
			(end -0.67945 -0.305054)
			(stroke
				(width 0.1)
				(type default)
			)
			(layer "F.Fab")
		)
		(fp_line
			(start -0.12065 0.3048)
			(end -0.67945 0.3048)
			(stroke
				(width 0.1)
				(type default)
			)
			(layer "F.Fab")
		)
		(fp_line
			(start 0.120396 0.3048)
			(end 0.120396 0.2794)
			(stroke
				(width 0.1)
				(type default)
			)
			(layer "F.Fab")
		)
		(fp_line
			(start 0.67945 0.3048)
			(end 0.120396 0.3048)
			(stroke
				(width 0.1)
				(type default)
			)
			(layer "F.Fab")
		)
		(fp_line
			(start -0.12065 0.2794)
			(end -0.12065 0.3048)
			(stroke
				(width 0.1)
				(type default)
			)
			(layer "F.Fab")
		)
		(fp_line
			(start 0.120396 0.2794)
			(end -0.12065 0.2794)
			(stroke
				(width 0.1)
				(type default)
			)
			(layer "F.Fab")
		)
		(fp_line
			(start -0.12065 -0.2794)
			(end 0.12065 -0.2794)
			(stroke
				(width 0.1)
				(type default)
			)
			(layer "F.Fab")
		)
		(fp_line
			(start 0.12065 -0.2794)
			(end 0.12065 -0.3048)
			(stroke
				(width 0.1)
				(type default)
			)
			(layer "F.Fab")
		)
		(fp_line
			(start 0.12065 -0.3048)
			(end 0.67945 -0.3048)
			(stroke
				(width 0.1)
				(type default)
			)
			(layer "F.Fab")
		)
		(fp_line
			(start 0.67945 -0.3048)
			(end 0.67945 0.3048)
			(stroke
				(width 0.1)
				(type default)
			)
			(layer "F.Fab")
		)
		(fp_line
			(start -0.67945 -0.305054)
			(end -0.12065 -0.305054)
			(stroke
				(width 0.1)
				(type default)
			)
			(layer "F.Fab")
		)
		(fp_line
			(start -0.12065 -0.305054)
			(end -0.12065 -0.2794)
			(stroke
				(width 0.1)
				(type default)
			)
			(layer "F.Fab")
		)
		(pad "1" smd circle
			(at -0.40005 0 270)
			(size 0 0)
			(layers "F.Cu" "F.Mask" "F.Paste")
			(net "P3V3_AUX")
		)
		(pad "2" smd circle
			(at 0.40005 0 270)
			(size 0 0)
			(layers "F.Cu" "F.Mask" "F.Paste")
			(net "P0V62_CPU0_RST_DDR_VREF")
		)
	)
	(footprint ""
		(layer "F.Cu")
		(at 434.443632 -107.17403 90)
		(property "Reference" "PC2086"
			(at 0 0 90)
			(layer "F.SilkS")
			(hide yes)
			(effects
				(font
					(size 1.27 1.27)
				)
			)
		)
		(property "Value" ""
			(at 0 0 90)
			(layer "F.Fab")
			(effects
				(font
					(size 1.27 1.27)
				)
			)
		)
		(duplicate_pad_numbers_are_jumpers no)
		(fp_line
			(start 0.7874 -0.4064)
			(end 0.7874 0.4064)
			(stroke
				(width 0.1524)
				(type default)
			)
			(layer "F.SilkS")
		)
		(fp_line
			(start -0.7874 -0.4064)
			(end 0.7874 -0.4064)
			(stroke
				(width 0.1524)
				(type default)
			)
			(layer "F.SilkS")
		)
		(fp_line
			(start 0.7874 0.4064)
			(end -0.7874 0.4064)
			(stroke
				(width 0.1524)
				(type default)
			)
			(layer "F.SilkS")
		)
		(fp_line
			(start -0.7874 0.4064)
			(end -0.7874 -0.4064)
			(stroke
				(width 0.1524)
				(type default)
			)
			(layer "F.SilkS")
		)
		(fp_line
			(start -0.12065 -0.305054)
			(end -0.12065 -0.2794)
			(stroke
				(width 0.1)
				(type default)
			)
			(layer "F.Fab")
		)
		(fp_line
			(start -0.67945 -0.305054)
			(end -0.12065 -0.305054)
			(stroke
				(width 0.1)
				(type default)
			)
			(layer "F.Fab")
		)
		(fp_line
			(start 0.67945 -0.3048)
			(end 0.67945 0.3048)
			(stroke
				(width 0.1)
				(type default)
			)
			(layer "F.Fab")
		)
		(fp_line
			(start 0.12065 -0.3048)
			(end 0.67945 -0.3048)
			(stroke
				(width 0.1)
				(type default)
			)
			(layer "F.Fab")
		)
		(fp_line
			(start 0.12065 -0.2794)
			(end 0.12065 -0.3048)
			(stroke
				(width 0.1)
				(type default)
			)
			(layer "F.Fab")
		)
		(fp_line
			(start -0.12065 -0.2794)
			(end 0.12065 -0.2794)
			(stroke
				(width 0.1)
				(type default)
			)
			(layer "F.Fab")
		)
		(fp_line
			(start 0.120396 0.2794)
			(end -0.12065 0.2794)
			(stroke
				(width 0.1)
				(type default)
			)
			(layer "F.Fab")
		)
		(fp_line
			(start -0.12065 0.2794)
			(end -0.12065 0.3048)
			(stroke
				(width 0.1)
				(type default)
			)
			(layer "F.Fab")
		)
		(fp_line
			(start 0.67945 0.3048)
			(end 0.120396 0.3048)
			(stroke
				(width 0.1)
				(type default)
			)
			(layer "F.Fab")
		)
		(fp_line
			(start 0.120396 0.3048)
			(end 0.120396 0.2794)
			(stroke
				(width 0.1)
				(type default)
			)
			(layer "F.Fab")
		)
		(fp_line
			(start -0.12065 0.3048)
			(end -0.67945 0.3048)
			(stroke
				(width 0.1)
				(type default)
			)
			(layer "F.Fab")
		)
		(fp_line
			(start -0.67945 0.3048)
			(end -0.67945 -0.305054)
			(stroke
				(width 0.1)
				(type default)
			)
			(layer "F.Fab")
		)
		(pad "1" smd circle
			(at -0.40005 0 90)
			(size 0 0)
			(layers "F.Cu" "F.Mask" "F.Paste")
			(net "P3V3_OCP_VCC_1")
		)
		(pad "2" smd circle
			(at 0.40005 0 90)
			(size 0 0)
			(layers "F.Cu" "F.Mask" "F.Paste")
			(net "GND")
		)
	)
)
